(kicad_pcb
	(version 20260206)
	(generator "pcbnew")
	(generator_version "10.0")
	(general
		(thickness 1.6)
		(legacy_teardrops no)
	)
	(paper "A4")
	(title_block
		(title "01162023_DA0F0TEBIF0_F0T_Expander_BD_F_brd_V02_OCP.brd")
		(comment 1 "Grand Teton / footprints 4614-4620 of 9728")
	)
	(layers
		(0 "F.Cu" signal "TOP")
		(4 "In1.Cu" signal "GND")
		(6 "In2.Cu" signal "VCC")
		(8 "In3.Cu" signal "VCC1")
		(10 "In4.Cu" signal "GND1")
		(12 "In5.Cu" signal "IN1")
		(14 "In6.Cu" signal "GND2")
		(16 "In7.Cu" signal "IN2")
		(18 "In8.Cu" signal "GND3")
		(20 "In9.Cu" signal "IN3")
		(22 "In10.Cu" signal "GND4")
		(24 "In11.Cu" signal "IN4")
		(26 "In12.Cu" signal "GND5")
		(28 "In13.Cu" signal "IN5")
		(30 "In14.Cu" signal "GND6")
		(32 "In15.Cu" signal "IN6")
		(34 "In16.Cu" signal "GND7")
		(2 "B.Cu" signal "BOTTOM")
		(9 "F.Adhes" user "F.Adhesive")
		(11 "B.Adhes" user "B.Adhesive")
		(13 "F.Paste" user "Package Geometry/Pastemask Top")
		(15 "B.Paste" user "Package Geometry/Pastemask Bottom")
		(5 "F.SilkS" user "Ref Des/Silkscreen Top")
		(7 "B.SilkS" user "Ref Des/Silkscreen Bottom")
		(1 "F.Mask" user "Board Geometry/Soldermask Top")
		(3 "B.Mask" user "Board Geometry/Soldermask Bottom")
		(17 "Dwgs.User" user "User.Drawings")
		(19 "Cmts.User" user "User.Comments")
		(21 "Eco1.User" user "User.Eco1")
		(23 "Eco2.User" user "User.Eco2")
		(25 "Edge.Cuts" user "Board Geometry/Outline")
		(27 "Margin" user)
		(31 "F.CrtYd" user "Package Geometry/Place Bound Top")
		(29 "B.CrtYd" user "Package Geometry/Place Bound Bottom")
		(35 "F.Fab" user "Ref Des/Assembly Top")
		(33 "B.Fab" user "Ref Des/Assembly Bottom")
	)
	(footprint ""
		(layer "F.Cu")
		(at 244.583458 -160.327848 180)
		(property "Reference" "PR7027"
			(at 0 0 180)
			(layer "F.SilkS")
			(hide yes)
			(effects
				(font
					(size 1.27 1.27)
				)
			)
		)
		(property "Value" ""
			(at 0 0 180)
			(layer "F.Fab")
			(effects
				(font
					(size 1.27 1.27)
				)
			)
		)
		(duplicate_pad_numbers_are_jumpers no)
		(fp_line
			(start 0.7874 0.4064)
			(end -0.7874 0.4064)
			(stroke
				(width 0.1524)
				(type default)
			)
			(layer "F.SilkS")
		)
		(fp_line
			(start 0.7874 -0.4064)
			(end 0.7874 0.4064)
			(stroke
				(width 0.1524)
				(type default)
			)
			(layer "F.SilkS")
		)
		(fp_line
			(start -0.7874 0.4064)
			(end -0.7874 -0.4064)
			(stroke
				(width 0.1524)
				(type default)
			)
			(layer "F.SilkS")
		)
		(fp_line
			(start -0.7874 -0.4064)
			(end 0.7874 -0.4064)
			(stroke
				(width 0.1524)
				(type default)
			)
			(layer "F.SilkS")
		)
		(fp_line
			(start 0.67945 0.3048)
			(end 0.120396 0.3048)
			(stroke
				(width 0.1)
				(type default)
			)
			(layer "F.Fab")
		)
		(fp_line
			(start 0.67945 -0.3048)
			(end 0.67945 0.3048)
			(stroke
				(width 0.1)
				(type default)
			)
			(layer "F.Fab")
		)
		(fp_line
			(start 0.12065 -0.2794)
			(end 0.12065 -0.3048)
			(stroke
				(width 0.1)
				(type default)
			)
			(layer "F.Fab")
		)
		(fp_line
			(start 0.12065 -0.3048)
			(end 0.67945 -0.3048)
			(stroke
				(width 0.1)
				(type default)
			)
			(layer "F.Fab")
		)
		(fp_line
			(start 0.120396 0.3048)
			(end 0.120396 0.2794)
			(stroke
				(width 0.1)
				(type default)
			)
			(layer "F.Fab")
		)
		(fp_line
			(start 0.120396 0.2794)
			(end -0.12065 0.2794)
			(stroke
				(width 0.1)
				(type default)
			)
			(layer "F.Fab")
		)
		(fp_line
			(start -0.12065 0.3048)
			(end -0.67945 0.3048)
			(stroke
				(width 0.1)
				(type default)
			)
			(layer "F.Fab")
		)
		(fp_line
			(start -0.12065 0.2794)
			(end -0.12065 0.3048)
			(stroke
				(width 0.1)
				(type default)
			)
			(layer "F.Fab")
		)
		(fp_line
			(start -0.12065 -0.2794)
			(end 0.12065 -0.2794)
			(stroke
				(width 0.1)
				(type default)
			)
			(layer "F.Fab")
		)
		(fp_line
			(start -0.12065 -0.305054)
			(end -0.12065 -0.2794)
			(stroke
				(width 0.1)
				(type default)
			)
			(layer "F.Fab")
		)
		(fp_line
			(start -0.67945 0.3048)
			(end -0.67945 -0.305054)
			(stroke
				(width 0.1)
				(type default)
			)
			(layer "F.Fab")
		)
		(fp_line
			(start -0.67945 -0.305054)
			(end -0.12065 -0.305054)
			(stroke
				(width 0.1)
				(type default)
			)
			(layer "F.Fab")
		)
		(pad "1" smd circle
			(at -0.40005 0 180)
			(size 0 0)
			(layers "F.Cu" "F.Mask" "F.Paste")
			(net "P12V_NIC4_CO_ISET")
		)
		(pad "2" smd circle
			(at 0.40005 0 180)
			(size 0 0)
			(layers "F.Cu" "F.Mask" "F.Paste")
			(net "P12V_NIC4_CO_ISET_R")
		)
	)
	(footprint ""
		(layer "F.Cu")
		(at 370.708428 -257.102102)
		(property "Reference" "Q20"
			(at -2.243836 0.85725 90)
			(unlocked yes)
			(layer "F.SilkS")
			(effects
				(font
					(size 0.7874 0.5842)
					(thickness 0.1524)
				)
			)
		)
		(property "Value" ""
			(at 0 0 0)
			(layer "F.Fab")
			(effects
				(font
					(size 1.27 1.27)
				)
			)
		)
		(duplicate_pad_numbers_are_jumpers no)
		(fp_line
			(start -1.376172 -1.199896)
			(end -0.508 -1.199896)
			(stroke
				(width 0.1524)
				(type default)
			)
			(layer "F.SilkS")
		)
		(fp_line
			(start -1.376172 1.199896)
			(end -1.376172 -1.199896)
			(stroke
				(width 0.1524)
				(type default)
			)
			(layer "F.SilkS")
		)
		(fp_line
			(start -0.508 -1.199896)
			(end 0 -0.762)
			(stroke
				(width 0.1524)
				(type default)
			)
			(layer "F.SilkS")
		)
		(fp_line
			(start 0 -0.762)
			(end 0.508 -1.199896)
			(stroke
				(width 0.1524)
				(type default)
			)
			(layer "F.SilkS")
		)
		(fp_line
			(start 0.508 -1.199896)
			(end 1.376172 -1.199896)
			(stroke
				(width 0.1524)
				(type default)
			)
			(layer "F.SilkS")
		)
		(fp_line
			(start 1.376172 -1.199896)
			(end 1.376172 1.199896)
			(stroke
				(width 0.1524)
				(type default)
			)
			(layer "F.SilkS")
		)
		(fp_line
			(start 1.376172 1.199896)
			(end -1.376172 1.199896)
			(stroke
				(width 0.1524)
				(type default)
			)
			(layer "F.SilkS")
		)
		(fp_poly
			(pts
				(xy -1.4605 -0.7493) (xy -2.2225 -1.1303) (xy -2.2225 -0.3683)
			)
			(stroke
				(width 0)
				(type default)
			)
			(fill yes)
			(layer "F.SilkS")
		)
		(fp_line
			(start -0.674878 -1.100074)
			(end 0.674878 -1.100074)
			(stroke
				(width 0.1)
				(type default)
			)
			(layer "F.Fab")
		)
		(fp_line
			(start -0.674878 1.100074)
			(end -0.674878 -1.100074)
			(stroke
				(width 0.1)
				(type default)
			)
			(layer "F.Fab")
		)
		(fp_line
			(start 0.674878 -1.100074)
			(end 0.674878 1.100074)
			(stroke
				(width 0.1)
				(type default)
			)
			(layer "F.Fab")
		)
		(fp_line
			(start 0.674878 1.100074)
			(end -0.674878 1.100074)
			(stroke
				(width 0.1)
				(type default)
			)
			(layer "F.Fab")
		)
		(fp_poly
			(pts
				(xy -1.4605 -0.7493) (xy -2.2225 -1.1303) (xy -2.2225 -0.3683)
			)
			(stroke
				(width 0)
				(type default)
			)
			(fill yes)
			(layer "F.Fab")
		)
		(pad "1" smd rect
			(at -0.899922 -0.750062 270)
			(size 0.6096 0.6096)
			(layers "F.Cu" "F.Mask" "F.Paste")
			(net "GND")
		)
		(pad "2" smd rect
			(at -0.899922 0 270)
			(size 0.4064 0.6096)
			(layers "F.Cu" "F.Mask" "F.Paste")
			(net "PEX3_SYS_ERR_R_N")
		)
		(pad "3" smd rect
			(at -0.899922 0.750062 270)
			(size 0.6096 0.6096)
			(layers "F.Cu" "F.Mask" "F.Paste")
			(net "PEX3_SYS_ERR_3V3_N")
		)
		(pad "4" smd rect
			(at 0.899922 0.750062 270)
			(size 0.6096 0.6096)
			(layers "F.Cu" "F.Mask" "F.Paste")
			(net "GND")
		)
		(pad "5" smd rect
			(at 0.899922 0 270)
			(size 0.4064 0.6096)
			(layers "F.Cu" "F.Mask" "F.Paste")
			(net "PEX3_SYS_ERR_N_G")
		)
		(pad "6" smd rect
			(at 0.899922 -0.750062 270)
			(size 0.6096 0.6096)
			(layers "F.Cu" "F.Mask" "F.Paste")
			(net "PEX3_SYS_ERR_N_G")
		)
	)
	(footprint ""
		(layer "F.Cu")
		(at 464.381088 -281.323034 -90)
		(property "Reference" "R1746"
			(at 0 0 270)
			(layer "F.SilkS")
			(hide yes)
			(effects
				(font
					(size 1.27 1.27)
				)
			)
		)
		(property "Value" ""
			(at 0 0 270)
			(layer "F.Fab")
			(effects
				(font
					(size 1.27 1.27)
				)
			)
		)
		(duplicate_pad_numbers_are_jumpers no)
		(fp_line
			(start -0.7874 0.4064)
			(end -0.7874 -0.4064)
			(stroke
				(width 0.1524)
				(type default)
			)
			(layer "F.SilkS")
		)
		(fp_line
			(start 0.7874 0.4064)
			(end -0.7874 0.4064)
			(stroke
				(width 0.1524)
				(type default)
			)
			(layer "F.SilkS")
		)
		(fp_line
			(start -0.7874 -0.4064)
			(end 0.7874 -0.4064)
			(stroke
				(width 0.1524)
				(type default)
			)
			(layer "F.SilkS")
		)
		(fp_line
			(start 0.7874 -0.4064)
			(end 0.7874 0.4064)
			(stroke
				(width 0.1524)
				(type default)
			)
			(layer "F.SilkS")
		)
		(fp_line
			(start -0.67945 0.3048)
			(end -0.67945 -0.305054)
			(stroke
				(width 0.1)
				(type default)
			)
			(layer "F.Fab")
		)
		(fp_line
			(start -0.12065 0.3048)
			(end -0.67945 0.3048)
			(stroke
				(width 0.1)
				(type default)
			)
			(layer "F.Fab")
		)
		(fp_line
			(start 0.120396 0.3048)
			(end 0.120396 0.2794)
			(stroke
				(width 0.1)
				(type default)
			)
			(layer "F.Fab")
		)
		(fp_line
			(start 0.67945 0.3048)
			(end 0.120396 0.3048)
			(stroke
				(width 0.1)
				(type default)
			)
			(layer "F.Fab")
		)
		(fp_line
			(start -0.12065 0.2794)
			(end -0.12065 0.3048)
			(stroke
				(width 0.1)
				(type default)
			)
			(layer "F.Fab")
		)
		(fp_line
			(start 0.120396 0.2794)
			(end -0.12065 0.2794)
			(stroke
				(width 0.1)
				(type default)
			)
			(layer "F.Fab")
		)
		(fp_line
			(start -0.12065 -0.2794)
			(end 0.12065 -0.2794)
			(stroke
				(width 0.1)
				(type default)
			)
			(layer "F.Fab")
		)
		(fp_line
			(start 0.12065 -0.2794)
			(end 0.12065 -0.3048)
			(stroke
				(width 0.1)
				(type default)
			)
			(layer "F.Fab")
		)
		(fp_line
			(start 0.12065 -0.3048)
			(end 0.67945 -0.3048)
			(stroke
				(width 0.1)
				(type default)
			)
			(layer "F.Fab")
		)
		(fp_line
			(start 0.67945 -0.3048)
			(end 0.67945 0.3048)
			(stroke
				(width 0.1)
				(type default)
			)
			(layer "F.Fab")
		)
		(fp_line
			(start -0.67945 -0.305054)
			(end -0.12065 -0.305054)
			(stroke
				(width 0.1)
				(type default)
			)
			(layer "F.Fab")
		)
		(fp_line
			(start -0.12065 -0.305054)
			(end -0.12065 -0.2794)
			(stroke
				(width 0.1)
				(type default)
			)
			(layer "F.Fab")
		)
		(pad "1" smd circle
			(at -0.40005 0 270)
			(size 0 0)
			(layers "F.Cu" "F.Mask" "F.Paste")
			(net "P3V3_AUX")
		)
		(pad "2" smd circle
			(at 0.40005 0 270)
			(size 0 0)
			(layers "F.Cu" "F.Mask" "F.Paste")
			(net "SMB_BIC_I2C6_MUX_PEX_ADC_R_SCL")
		)
	)
	(footprint ""
		(layer "F.Cu")
		(at 235.690664 -204.44206 90)
		(property "Reference" "R5480"
			(at 0 0 90)
			(layer "F.SilkS")
			(hide yes)
			(effects
				(font
					(size 1.27 1.27)
				)
			)
		)
		(property "Value" ""
			(at 0 0 90)
			(layer "F.Fab")
			(effects
				(font
					(size 1.27 1.27)
				)
			)
		)
		(duplicate_pad_numbers_are_jumpers no)
		(fp_line
			(start 0.7874 -0.4064)
			(end 0.7874 0.4064)
			(stroke
				(width 0.1524)
				(type default)
			)
			(layer "F.SilkS")
		)
		(fp_line
			(start -0.7874 -0.4064)
			(end 0.7874 -0.4064)
			(stroke
				(width 0.1524)
				(type default)
			)
			(layer "F.SilkS")
		)
		(fp_line
			(start 0.7874 0.4064)
			(end -0.7874 0.4064)
			(stroke
				(width 0.1524)
				(type default)
			)
			(layer "F.SilkS")
		)
		(fp_line
			(start -0.7874 0.4064)
			(end -0.7874 -0.4064)
			(stroke
				(width 0.1524)
				(type default)
			)
			(layer "F.SilkS")
		)
		(fp_line
			(start -0.12065 -0.305054)
			(end -0.12065 -0.2794)
			(stroke
				(width 0.1)
				(type default)
			)
			(layer "F.Fab")
		)
		(fp_line
			(start -0.67945 -0.305054)
			(end -0.12065 -0.305054)
			(stroke
				(width 0.1)
				(type default)
			)
			(layer "F.Fab")
		)
		(fp_line
			(start 0.67945 -0.3048)
			(end 0.67945 0.3048)
			(stroke
				(width 0.1)
				(type default)
			)
			(layer "F.Fab")
		)
		(fp_line
			(start 0.12065 -0.3048)
			(end 0.67945 -0.3048)
			(stroke
				(width 0.1)
				(type default)
			)
			(layer "F.Fab")
		)
		(fp_line
			(start 0.12065 -0.2794)
			(end 0.12065 -0.3048)
			(stroke
				(width 0.1)
				(type default)
			)
			(layer "F.Fab")
		)
		(fp_line
			(start -0.12065 -0.2794)
			(end 0.12065 -0.2794)
			(stroke
				(width 0.1)
				(type default)
			)
			(layer "F.Fab")
		)
		(fp_line
			(start 0.120396 0.2794)
			(end -0.12065 0.2794)
			(stroke
				(width 0.1)
				(type default)
			)
			(layer "F.Fab")
		)
		(fp_line
			(start -0.12065 0.2794)
			(end -0.12065 0.3048)
			(stroke
				(width 0.1)
				(type default)
			)
			(layer "F.Fab")
		)
		(fp_line
			(start 0.67945 0.3048)
			(end 0.120396 0.3048)
			(stroke
				(width 0.1)
				(type default)
			)
			(layer "F.Fab")
		)
		(fp_line
			(start 0.120396 0.3048)
			(end 0.120396 0.2794)
			(stroke
				(width 0.1)
				(type default)
			)
			(layer "F.Fab")
		)
		(fp_line
			(start -0.12065 0.3048)
			(end -0.67945 0.3048)
			(stroke
				(width 0.1)
				(type default)
			)
			(layer "F.Fab")
		)
		(fp_line
			(start -0.67945 0.3048)
			(end -0.67945 -0.305054)
			(stroke
				(width 0.1)
				(type default)
			)
			(layer "F.Fab")
		)
		(pad "1" smd circle
			(at -0.40005 0 90)
			(size 0 0)
			(layers "F.Cu" "F.Mask" "F.Paste")
			(net "RST_BIC_SRST_R_N")
		)
		(pad "2" smd circle
			(at 0.40005 0 90)
			(size 0 0)
			(layers "F.Cu" "F.Mask" "F.Paste")
			(net "RST_BIC_SRST_BIC_N")
		)
	)
	(footprint ""
		(layer "F.Cu")
		(at 237.924848 -85.551518 180)
		(property "Reference" "R6285"
			(at 0 0 180)
			(layer "F.SilkS")
			(hide yes)
			(effects
				(font
					(size 1.27 1.27)
				)
			)
		)
		(property "Value" ""
			(at 0 0 180)
			(layer "F.Fab")
			(effects
				(font
					(size 1.27 1.27)
				)
			)
		)
		(duplicate_pad_numbers_are_jumpers no)
		(fp_line
			(start 0.7874 0.4064)
			(end 0.004318 0.4064)
			(stroke
				(width 0.1524)
				(type default)
			)
			(layer "F.SilkS")
		)
		(fp_line
			(start 0.7874 -0.4064)
			(end 0.7874 0.4064)
			(stroke
				(width 0.1524)
				(type default)
			)
			(layer "F.SilkS")
		)
		(fp_line
			(start -0.7874 -0.4064)
			(end 0.7874 -0.4064)
			(stroke
				(width 0.1524)
				(type default)
			)
			(layer "F.SilkS")
		)
		(fp_line
			(start 0.67945 0.3048)
			(end 0.120396 0.3048)
			(stroke
				(width 0.1)
				(type default)
			)
			(layer "F.Fab")
		)
		(fp_line
			(start 0.67945 -0.3048)
			(end 0.67945 0.3048)
			(stroke
				(width 0.1)
				(type default)
			)
			(layer "F.Fab")
		)
		(fp_line
			(start 0.12065 -0.2794)
			(end 0.12065 -0.3048)
			(stroke
				(width 0.1)
				(type default)
			)
			(layer "F.Fab")
		)
		(fp_line
			(start 0.12065 -0.3048)
			(end 0.67945 -0.3048)
			(stroke
				(width 0.1)
				(type default)
			)
			(layer "F.Fab")
		)
		(fp_line
			(start 0.120396 0.3048)
			(end 0.120396 0.2794)
			(stroke
				(width 0.1)
				(type default)
			)
			(layer "F.Fab")
		)
		(fp_line
			(start 0.120396 0.2794)
			(end -0.12065 0.2794)
			(stroke
				(width 0.1)
				(type default)
			)
			(layer "F.Fab")
		)
		(fp_line
			(start -0.12065 0.3048)
			(end -0.67945 0.3048)
			(stroke
				(width 0.1)
				(type default)
			)
			(layer "F.Fab")
		)
		(fp_line
			(start -0.12065 0.2794)
			(end -0.12065 0.3048)
			(stroke
				(width 0.1)
				(type default)
			)
			(layer "F.Fab")
		)
		(fp_line
			(start -0.12065 -0.2794)
			(end 0.12065 -0.2794)
			(stroke
				(width 0.1)
				(type default)
			)
			(layer "F.Fab")
		)
		(fp_line
			(start -0.12065 -0.305054)
			(end -0.12065 -0.2794)
			(stroke
				(width 0.1)
				(type default)
			)
			(layer "F.Fab")
		)
		(fp_line
			(start -0.67945 0.3048)
			(end -0.67945 -0.305054)
			(stroke
				(width 0.1)
				(type default)
			)
			(layer "F.Fab")
		)
		(fp_line
			(start -0.67945 -0.305054)
			(end -0.12065 -0.305054)
			(stroke
				(width 0.1)
				(type default)
			)
			(layer "F.Fab")
		)
		(pad "1" smd rect
			(at -0.40005 0)
			(size 0.4572 0.508)
			(layers "F.Cu" "F.Mask" "F.Paste")
			(net "USB2_FT4232_CLI_DN")
		)
		(pad "2" smd rect
			(at 0.40005 0)
			(size 0.4572 0.508)
			(layers "F.Cu" "F.Mask" "F.Paste")
			(net "GND")
		)
	)
	(footprint ""
		(layer "F.Cu")
		(at 174.596552 -343.952322 90)
		(property "Reference" "C390"
			(at 0 0 90)
			(layer "F.SilkS")
			(hide yes)
			(effects
				(font
					(size 1.27 1.27)
				)
			)
		)
		(property "Value" ""
			(at 0 0 90)
			(layer "F.Fab")
			(effects
				(font
					(size 1.27 1.27)
				)
			)
		)
		(duplicate_pad_numbers_are_jumpers no)
		(fp_line
			(start 0.299974 -0.150114)
			(end 0.299974 0.150114)
			(stroke
				(width 0.1)
				(type default)
			)
			(layer "F.Fab")
		)
		(fp_line
			(start -0.299974 -0.150114)
			(end 0.299974 -0.150114)
			(stroke
				(width 0.1)
				(type default)
			)
			(layer "F.Fab")
		)
		(fp_line
			(start 0.299974 0.150114)
			(end -0.299974 0.150114)
			(stroke
				(width 0.1)
				(type default)
			)
			(layer "F.Fab")
		)
		(fp_line
			(start -0.299974 0.150114)
			(end -0.299974 -0.150114)
			(stroke
				(width 0.1)
				(type default)
			)
			(layer "F.Fab")
		)
		(pad "1" smd rect
			(at -0.2667 0 90)
			(size 0.3048 0.381)
			(layers "F.Cu" "F.Mask" "F.Paste")
			(net "P5E_PEX1_STN7_TX_DP<118>")
		)
		(pad "2" smd rect
			(at 0.2667 0 90)
			(size 0.3048 0.381)
			(layers "F.Cu" "F.Mask" "F.Paste")
			(net "P5E_PEX1_STN7_TX_C_DP<118>")
		)
	)
	(footprint ""
		(layer "F.Cu")
		(at 392.092434 -29.139642 180)
		(property "Reference" "C712"
			(at 0 0 180)
			(layer "F.SilkS")
			(hide yes)
			(effects
				(font
					(size 1.27 1.27)
				)
			)
		)
		(property "Value" ""
			(at 0 0 180)
			(layer "F.Fab")
			(effects
				(font
					(size 1.27 1.27)
				)
			)
		)
		(duplicate_pad_numbers_are_jumpers no)
		(fp_line
			(start 0.299974 0.150114)
			(end -0.299974 0.150114)
			(stroke
				(width 0.1)
				(type default)
			)
			(layer "F.Fab")
		)
		(fp_line
			(start 0.299974 -0.150114)
			(end 0.299974 0.150114)
			(stroke
				(width 0.1)
				(type default)
			)
			(layer "F.Fab")
		)
		(fp_line
			(start -0.299974 0.150114)
			(end -0.299974 -0.150114)
			(stroke
				(width 0.1)
				(type default)
			)
			(layer "F.Fab")
		)
		(fp_line
			(start -0.299974 -0.150114)
			(end 0.299974 -0.150114)
			(stroke
				(width 0.1)
				(type default)
			)
			(layer "F.Fab")
		)
		(pad "1" smd rect
			(at -0.2667 0 180)
			(size 0.3048 0.381)
			(layers "F.Cu" "F.Mask" "F.Paste")
			(net "P5E_PEX3_STN2_TX_DP<40>")
		)
		(pad "2" smd rect
			(at 0.2667 0 180)
			(size 0.3048 0.381)
			(layers "F.Cu" "F.Mask" "F.Paste")
			(net "P5E_PEX3_STN2_TX_C_DP<40>")
		)
	)
)
